(kicad_pcb
	(version 20260206)
	(generator "pcbnew")
	(generator_version "10.0")
	(general
		(thickness 1.6)
		(legacy_teardrops no)
	)
	(paper "A4")
	(title_block
		(title "03242023_DA0F0TMBIJ0_F0T_Motherboard_J_brd_V01_OCP.brd")
		(comment 1 "Grand Teton / footprints 4824-4830 of 6105")
	)
	(layers
		(0 "F.Cu" signal "TOP")
		(4 "In1.Cu" signal "GND")
		(6 "In2.Cu" signal "IN1")
		(8 "In3.Cu" signal "GND1")
		(10 "In4.Cu" signal "IN2")
		(12 "In5.Cu" signal "GND2")
		(14 "In6.Cu" signal "IN3")
		(16 "In7.Cu" signal "GND3")
		(18 "In8.Cu" signal "VCC")
		(20 "In9.Cu" signal "VCC1")
		(22 "In10.Cu" signal "GND4")
		(24 "In11.Cu" signal "IN4")
		(26 "In12.Cu" signal "GND5")
		(28 "In13.Cu" signal "IN5")
		(30 "In14.Cu" signal "GND6")
		(32 "In15.Cu" signal "IN6")
		(34 "In16.Cu" signal "GND7")
		(2 "B.Cu" signal "BOTTOM")
		(9 "F.Adhes" user "F.Adhesive")
		(11 "B.Adhes" user "B.Adhesive")
		(13 "F.Paste" user "Package Geometry/Pastemask Top")
		(15 "B.Paste" user "Package Geometry/Pastemask Bottom")
		(5 "F.SilkS" user "Ref Des/Silkscreen Top")
		(7 "B.SilkS" user "Ref Des/Silkscreen Bottom")
		(1 "F.Mask" user "Board Geometry/Soldermask Top")
		(3 "B.Mask" user "Board Geometry/Soldermask Bottom")
		(17 "Dwgs.User" user "User.Drawings")
		(19 "Cmts.User" user "User.Comments")
		(21 "Eco1.User" user "User.Eco1")
		(23 "Eco2.User" user "User.Eco2")
		(25 "Edge.Cuts" user "Board Geometry/Outline")
		(27 "Margin" user)
		(31 "F.CrtYd" user "Package Geometry/Place Bound Top")
		(29 "B.CrtYd" user "Package Geometry/Place Bound Bottom")
		(35 "F.Fab" user "Ref Des/Assembly Top")
		(33 "B.Fab" user "Ref Des/Assembly Bottom")
	)
	(footprint ""
		(layer "B.Cu")
		(at 178.06035 -106.045 180)
		(property "Reference" "R164"
			(at 0 0 0)
			(layer "B.SilkS")
			(hide yes)
			(effects
				(font
					(size 1.27 1.27)
				)
				(justify mirror)
			)
		)
		(property "Value" ""
			(at 0 0 0)
			(layer "B.Fab")
			(effects
				(font
					(size 1.27 1.27)
				)
				(justify mirror)
			)
		)
		(duplicate_pad_numbers_are_jumpers no)
		(fp_line
			(start 0.7874 0.4064)
			(end 0.7874 -0.4064)
			(stroke
				(width 0.1524)
				(type default)
			)
			(layer "B.SilkS")
		)
		(fp_line
			(start 0.7874 -0.4064)
			(end -0.7874 -0.4064)
			(stroke
				(width 0.1524)
				(type default)
			)
			(layer "B.SilkS")
		)
		(fp_line
			(start -0.7874 0.4064)
			(end 0.7874 0.4064)
			(stroke
				(width 0.1524)
				(type default)
			)
			(layer "B.SilkS")
		)
		(fp_line
			(start -0.7874 -0.4064)
			(end -0.7874 0.4064)
			(stroke
				(width 0.1524)
				(type default)
			)
			(layer "B.SilkS")
		)
		(fp_line
			(start 0.67945 0.3048)
			(end 0.67945 -0.305054)
			(stroke
				(width 0.1)
				(type default)
			)
			(layer "B.Fab")
		)
		(fp_line
			(start 0.67945 -0.305054)
			(end 0.12065 -0.305054)
			(stroke
				(width 0.1)
				(type default)
			)
			(layer "B.Fab")
		)
		(fp_line
			(start 0.12065 0.3048)
			(end 0.67945 0.3048)
			(stroke
				(width 0.1)
				(type default)
			)
			(layer "B.Fab")
		)
		(fp_line
			(start 0.12065 0.2794)
			(end 0.12065 0.3048)
			(stroke
				(width 0.1)
				(type default)
			)
			(layer "B.Fab")
		)
		(fp_line
			(start 0.12065 -0.2794)
			(end -0.12065 -0.2794)
			(stroke
				(width 0.1)
				(type default)
			)
			(layer "B.Fab")
		)
		(fp_line
			(start 0.12065 -0.305054)
			(end 0.12065 -0.2794)
			(stroke
				(width 0.1)
				(type default)
			)
			(layer "B.Fab")
		)
		(fp_line
			(start -0.120396 0.3048)
			(end -0.120396 0.2794)
			(stroke
				(width 0.1)
				(type default)
			)
			(layer "B.Fab")
		)
		(fp_line
			(start -0.120396 0.2794)
			(end 0.12065 0.2794)
			(stroke
				(width 0.1)
				(type default)
			)
			(layer "B.Fab")
		)
		(fp_line
			(start -0.12065 -0.2794)
			(end -0.12065 -0.3048)
			(stroke
				(width 0.1)
				(type default)
			)
			(layer "B.Fab")
		)
		(fp_line
			(start -0.12065 -0.3048)
			(end -0.67945 -0.3048)
			(stroke
				(width 0.1)
				(type default)
			)
			(layer "B.Fab")
		)
		(fp_line
			(start -0.67945 0.3048)
			(end -0.120396 0.3048)
			(stroke
				(width 0.1)
				(type default)
			)
			(layer "B.Fab")
		)
		(fp_line
			(start -0.67945 -0.3048)
			(end -0.67945 0.3048)
			(stroke
				(width 0.1)
				(type default)
			)
			(layer "B.Fab")
		)
		(pad "1" smd circle
			(at 0.40005 0)
			(size 0 0)
			(layers "B.Cu" "B.Mask" "B.Paste")
			(net "PWRGD_DRAMPWRGD_CPU0_EF_R_LVC1")
		)
		(pad "2" smd circle
			(at -0.40005 0)
			(size 0 0)
			(layers "B.Cu" "B.Mask" "B.Paste")
			(net "PWRGD_DRAMPWRGD_CPU0_EF_LVC1_R2")
		)
	)
	(footprint ""
		(layer "B.Cu")
		(at 352.777298 -235.916724 180)
		(property "Reference" "C1"
			(at 0 0 0)
			(layer "B.SilkS")
			(hide yes)
			(effects
				(font
					(size 1.27 1.27)
				)
				(justify mirror)
			)
		)
		(property "Value" ""
			(at 0 0 0)
			(layer "B.Fab")
			(effects
				(font
					(size 1.27 1.27)
				)
				(justify mirror)
			)
		)
		(duplicate_pad_numbers_are_jumpers no)
		(fp_line
			(start 0.7874 0.4064)
			(end 0.7874 -0.4064)
			(stroke
				(width 0.1524)
				(type default)
			)
			(layer "B.SilkS")
		)
		(fp_line
			(start 0.7874 -0.4064)
			(end -0.7874 -0.4064)
			(stroke
				(width 0.1524)
				(type default)
			)
			(layer "B.SilkS")
		)
		(fp_line
			(start -0.7874 0.4064)
			(end 0.7874 0.4064)
			(stroke
				(width 0.1524)
				(type default)
			)
			(layer "B.SilkS")
		)
		(fp_line
			(start -0.7874 -0.4064)
			(end -0.7874 0.4064)
			(stroke
				(width 0.1524)
				(type default)
			)
			(layer "B.SilkS")
		)
		(fp_line
			(start 0.67945 0.3048)
			(end 0.67945 -0.305054)
			(stroke
				(width 0.1)
				(type default)
			)
			(layer "B.Fab")
		)
		(fp_line
			(start 0.67945 -0.305054)
			(end 0.12065 -0.305054)
			(stroke
				(width 0.1)
				(type default)
			)
			(layer "B.Fab")
		)
		(fp_line
			(start 0.12065 0.3048)
			(end 0.67945 0.3048)
			(stroke
				(width 0.1)
				(type default)
			)
			(layer "B.Fab")
		)
		(fp_line
			(start 0.12065 0.2794)
			(end 0.12065 0.3048)
			(stroke
				(width 0.1)
				(type default)
			)
			(layer "B.Fab")
		)
		(fp_line
			(start 0.12065 -0.2794)
			(end -0.12065 -0.2794)
			(stroke
				(width 0.1)
				(type default)
			)
			(layer "B.Fab")
		)
		(fp_line
			(start 0.12065 -0.305054)
			(end 0.12065 -0.2794)
			(stroke
				(width 0.1)
				(type default)
			)
			(layer "B.Fab")
		)
		(fp_line
			(start -0.120396 0.3048)
			(end -0.120396 0.2794)
			(stroke
				(width 0.1)
				(type default)
			)
			(layer "B.Fab")
		)
		(fp_line
			(start -0.120396 0.2794)
			(end 0.12065 0.2794)
			(stroke
				(width 0.1)
				(type default)
			)
			(layer "B.Fab")
		)
		(fp_line
			(start -0.12065 -0.2794)
			(end -0.12065 -0.3048)
			(stroke
				(width 0.1)
				(type default)
			)
			(layer "B.Fab")
		)
		(fp_line
			(start -0.12065 -0.3048)
			(end -0.67945 -0.3048)
			(stroke
				(width 0.1)
				(type default)
			)
			(layer "B.Fab")
		)
		(fp_line
			(start -0.67945 0.3048)
			(end -0.120396 0.3048)
			(stroke
				(width 0.1)
				(type default)
			)
			(layer "B.Fab")
		)
		(fp_line
			(start -0.67945 -0.3048)
			(end -0.67945 0.3048)
			(stroke
				(width 0.1)
				(type default)
			)
			(layer "B.Fab")
		)
		(pad "1" smd circle
			(at 0.40005 0)
			(size 0 0)
			(layers "B.Cu" "B.Mask" "B.Paste")
			(net "P3V3_AUX")
		)
		(pad "2" smd circle
			(at -0.40005 0)
			(size 0 0)
			(layers "B.Cu" "B.Mask" "B.Paste")
			(net "GND")
		)
	)
	(footprint ""
		(layer "B.Cu")
		(at 185.521346 -321.554856 -90)
		(property "Reference" "C89"
			(at 0 0 90)
			(layer "B.SilkS")
			(hide yes)
			(effects
				(font
					(size 1.27 1.27)
				)
				(justify mirror)
			)
		)
		(property "Value" ""
			(at 0 0 90)
			(layer "B.Fab")
			(effects
				(font
					(size 1.27 1.27)
				)
				(justify mirror)
			)
		)
		(duplicate_pad_numbers_are_jumpers no)
		(fp_line
			(start -1.524 0.762)
			(end 1.524 0.762)
			(stroke
				(width 0.1524)
				(type default)
			)
			(layer "B.SilkS")
		)
		(fp_line
			(start 1.524 0.762)
			(end 1.524 -0.762)
			(stroke
				(width 0.1524)
				(type default)
			)
			(layer "B.SilkS")
		)
		(fp_line
			(start -1.524 -0.762)
			(end -1.524 0.762)
			(stroke
				(width 0.1524)
				(type default)
			)
			(layer "B.SilkS")
		)
		(fp_line
			(start 1.524 -0.762)
			(end -1.524 -0.762)
			(stroke
				(width 0.1524)
				(type default)
			)
			(layer "B.SilkS")
		)
		(fp_line
			(start -1.1049 0.724916)
			(end -1.1049 -0.724916)
			(stroke
				(width 0.1)
				(type default)
			)
			(layer "B.Fab")
		)
		(fp_line
			(start 1.1049 0.724916)
			(end -1.1049 0.724916)
			(stroke
				(width 0.1)
				(type default)
			)
			(layer "B.Fab")
		)
		(fp_line
			(start -1.1049 -0.724916)
			(end 1.1049 -0.724916)
			(stroke
				(width 0.1)
				(type default)
			)
			(layer "B.Fab")
		)
		(fp_line
			(start 1.1049 -0.724916)
			(end 1.1049 0.724916)
			(stroke
				(width 0.1)
				(type default)
			)
			(layer "B.Fab")
		)
		(pad "1" smd rect
			(at 0.889 0 270)
			(size 1.016 1.27)
			(layers "B.Cu" "B.Mask" "B.Paste")
			(net "P12V_S3_AUX_CPU1_NVDIMM")
		)
		(pad "2" smd rect
			(at -0.889 0 270)
			(size 1.016 1.27)
			(layers "B.Cu" "B.Mask" "B.Paste")
			(net "GND")
		)
	)
	(footprint ""
		(layer "B.Cu")
		(at 335.099152 -31.394908 90)
		(property "Reference" "R499"
			(at 0 0 90)
			(layer "B.SilkS")
			(hide yes)
			(effects
				(font
					(size 1.27 1.27)
				)
				(justify mirror)
			)
		)
		(property "Value" ""
			(at 0 0 90)
			(layer "B.Fab")
			(effects
				(font
					(size 1.27 1.27)
				)
				(justify mirror)
			)
		)
		(duplicate_pad_numbers_are_jumpers no)
		(fp_line
			(start 0.7874 -0.4064)
			(end -0.7874 -0.4064)
			(stroke
				(width 0.1524)
				(type default)
			)
			(layer "B.SilkS")
		)
		(fp_line
			(start -0.7874 -0.4064)
			(end -0.7874 0.4064)
			(stroke
				(width 0.1524)
				(type default)
			)
			(layer "B.SilkS")
		)
		(fp_line
			(start 0.7874 0.4064)
			(end 0.7874 -0.4064)
			(stroke
				(width 0.1524)
				(type default)
			)
			(layer "B.SilkS")
		)
		(fp_line
			(start -0.7874 0.4064)
			(end 0.7874 0.4064)
			(stroke
				(width 0.1524)
				(type default)
			)
			(layer "B.SilkS")
		)
		(fp_line
			(start 0.67945 -0.305054)
			(end 0.12065 -0.305054)
			(stroke
				(width 0.1)
				(type default)
			)
			(layer "B.Fab")
		)
		(fp_line
			(start 0.12065 -0.305054)
			(end 0.12065 -0.2794)
			(stroke
				(width 0.1)
				(type default)
			)
			(layer "B.Fab")
		)
		(fp_line
			(start -0.12065 -0.3048)
			(end -0.67945 -0.3048)
			(stroke
				(width 0.1)
				(type default)
			)
			(layer "B.Fab")
		)
		(fp_line
			(start -0.67945 -0.3048)
			(end -0.67945 0.3048)
			(stroke
				(width 0.1)
				(type default)
			)
			(layer "B.Fab")
		)
		(fp_line
			(start 0.12065 -0.2794)
			(end -0.12065 -0.2794)
			(stroke
				(width 0.1)
				(type default)
			)
			(layer "B.Fab")
		)
		(fp_line
			(start -0.12065 -0.2794)
			(end -0.12065 -0.3048)
			(stroke
				(width 0.1)
				(type default)
			)
			(layer "B.Fab")
		)
		(fp_line
			(start 0.12065 0.2794)
			(end 0.12065 0.3048)
			(stroke
				(width 0.1)
				(type default)
			)
			(layer "B.Fab")
		)
		(fp_line
			(start -0.120396 0.2794)
			(end 0.12065 0.2794)
			(stroke
				(width 0.1)
				(type default)
			)
			(layer "B.Fab")
		)
		(fp_line
			(start 0.67945 0.3048)
			(end 0.67945 -0.305054)
			(stroke
				(width 0.1)
				(type default)
			)
			(layer "B.Fab")
		)
		(fp_line
			(start 0.12065 0.3048)
			(end 0.67945 0.3048)
			(stroke
				(width 0.1)
				(type default)
			)
			(layer "B.Fab")
		)
		(fp_line
			(start -0.120396 0.3048)
			(end -0.120396 0.2794)
			(stroke
				(width 0.1)
				(type default)
			)
			(layer "B.Fab")
		)
		(fp_line
			(start -0.67945 0.3048)
			(end -0.120396 0.3048)
			(stroke
				(width 0.1)
				(type default)
			)
			(layer "B.Fab")
		)
		(pad "1" smd circle
			(at 0.40005 0 270)
			(size 0 0)
			(layers "B.Cu" "B.Mask" "B.Paste")
			(net "SPI_PCH_CLK")
		)
		(pad "2" smd circle
			(at -0.40005 0 270)
			(size 0 0)
			(layers "B.Cu" "B.Mask" "B.Paste")
			(net "SPI_SYS_CLK")
		)
	)
	(footprint ""
		(layer "B.Cu")
		(at 355.91369 -324.911466 -90)
		(property "Reference" "PC313_P0_2"
			(at 0 0 90)
			(layer "B.SilkS")
			(hide yes)
			(effects
				(font
					(size 1.27 1.27)
				)
				(justify mirror)
			)
		)
		(property "Value" ""
			(at 0 0 90)
			(layer "B.Fab")
			(effects
				(font
					(size 1.27 1.27)
				)
				(justify mirror)
			)
		)
		(duplicate_pad_numbers_are_jumpers no)
		(fp_line
			(start -1.524 0.762)
			(end 1.524 0.762)
			(stroke
				(width 0.1524)
				(type default)
			)
			(layer "B.SilkS")
		)
		(fp_line
			(start 1.524 0.762)
			(end 1.524 -0.762)
			(stroke
				(width 0.1524)
				(type default)
			)
			(layer "B.SilkS")
		)
		(fp_line
			(start -1.524 -0.762)
			(end -1.524 0.762)
			(stroke
				(width 0.1524)
				(type default)
			)
			(layer "B.SilkS")
		)
		(fp_line
			(start 1.524 -0.762)
			(end -1.524 -0.762)
			(stroke
				(width 0.1524)
				(type default)
			)
			(layer "B.SilkS")
		)
		(fp_line
			(start -1.1049 0.724916)
			(end -1.1049 -0.724916)
			(stroke
				(width 0.1)
				(type default)
			)
			(layer "B.Fab")
		)
		(fp_line
			(start 1.1049 0.724916)
			(end -1.1049 0.724916)
			(stroke
				(width 0.1)
				(type default)
			)
			(layer "B.Fab")
		)
		(fp_line
			(start -1.1049 -0.724916)
			(end 1.1049 -0.724916)
			(stroke
				(width 0.1)
				(type default)
			)
			(layer "B.Fab")
		)
		(fp_line
			(start 1.1049 -0.724916)
			(end 1.1049 0.724916)
			(stroke
				(width 0.1)
				(type default)
			)
			(layer "B.Fab")
		)
		(pad "1" smd rect
			(at 0.889 0 270)
			(size 1.016 1.27)
			(layers "B.Cu" "B.Mask" "B.Paste")
			(net "PVCCIN_CPU0")
		)
		(pad "2" smd rect
			(at -0.889 0 270)
			(size 1.016 1.27)
			(layers "B.Cu" "B.Mask" "B.Paste")
			(net "GND")
		)
	)
	(footprint ""
		(layer "B.Cu")
		(at 161.29 -13.426948 90)
		(property "Reference" "R4507"
			(at 0 0 90)
			(layer "B.SilkS")
			(hide yes)
			(effects
				(font
					(size 1.27 1.27)
				)
				(justify mirror)
			)
		)
		(property "Value" ""
			(at 0 0 90)
			(layer "B.Fab")
			(effects
				(font
					(size 1.27 1.27)
				)
				(justify mirror)
			)
		)
		(duplicate_pad_numbers_are_jumpers no)
		(fp_line
			(start 0.7874 -0.4064)
			(end -0.7874 -0.4064)
			(stroke
				(width 0.1524)
				(type default)
			)
			(layer "B.SilkS")
		)
		(fp_line
			(start -0.7874 -0.4064)
			(end -0.7874 0.4064)
			(stroke
				(width 0.1524)
				(type default)
			)
			(layer "B.SilkS")
		)
		(fp_line
			(start 0.7874 0.4064)
			(end 0.7874 -0.4064)
			(stroke
				(width 0.1524)
				(type default)
			)
			(layer "B.SilkS")
		)
		(fp_line
			(start -0.7874 0.4064)
			(end 0.7874 0.4064)
			(stroke
				(width 0.1524)
				(type default)
			)
			(layer "B.SilkS")
		)
		(fp_line
			(start 0.67945 -0.305054)
			(end 0.12065 -0.305054)
			(stroke
				(width 0.1)
				(type default)
			)
			(layer "B.Fab")
		)
		(fp_line
			(start 0.12065 -0.305054)
			(end 0.12065 -0.2794)
			(stroke
				(width 0.1)
				(type default)
			)
			(layer "B.Fab")
		)
		(fp_line
			(start -0.12065 -0.3048)
			(end -0.67945 -0.3048)
			(stroke
				(width 0.1)
				(type default)
			)
			(layer "B.Fab")
		)
		(fp_line
			(start -0.67945 -0.3048)
			(end -0.67945 0.3048)
			(stroke
				(width 0.1)
				(type default)
			)
			(layer "B.Fab")
		)
		(fp_line
			(start 0.12065 -0.2794)
			(end -0.12065 -0.2794)
			(stroke
				(width 0.1)
				(type default)
			)
			(layer "B.Fab")
		)
		(fp_line
			(start -0.12065 -0.2794)
			(end -0.12065 -0.3048)
			(stroke
				(width 0.1)
				(type default)
			)
			(layer "B.Fab")
		)
		(fp_line
			(start 0.12065 0.2794)
			(end 0.12065 0.3048)
			(stroke
				(width 0.1)
				(type default)
			)
			(layer "B.Fab")
		)
		(fp_line
			(start -0.120396 0.2794)
			(end 0.12065 0.2794)
			(stroke
				(width 0.1)
				(type default)
			)
			(layer "B.Fab")
		)
		(fp_line
			(start 0.67945 0.3048)
			(end 0.67945 -0.305054)
			(stroke
				(width 0.1)
				(type default)
			)
			(layer "B.Fab")
		)
		(fp_line
			(start 0.12065 0.3048)
			(end 0.67945 0.3048)
			(stroke
				(width 0.1)
				(type default)
			)
			(layer "B.Fab")
		)
		(fp_line
			(start -0.120396 0.3048)
			(end -0.120396 0.2794)
			(stroke
				(width 0.1)
				(type default)
			)
			(layer "B.Fab")
		)
		(fp_line
			(start -0.67945 0.3048)
			(end -0.120396 0.3048)
			(stroke
				(width 0.1)
				(type default)
			)
			(layer "B.Fab")
		)
		(pad "1" smd circle
			(at 0.40005 0 270)
			(size 0 0)
			(layers "B.Cu" "B.Mask" "B.Paste")
			(net "SMB_SML0_3V3AUX_SDA")
		)
		(pad "2" smd circle
			(at -0.40005 0 270)
			(size 0 0)
			(layers "B.Cu" "B.Mask" "B.Paste")
			(net "SMB_SML0_3V3AUX_SDA_R1")
		)
	)
	(footprint ""
		(layer "B.Cu")
		(at 418.57549 -149.950424)
		(property "Reference" "PC179"
			(at 0 0 0)
			(layer "B.SilkS")
			(hide yes)
			(effects
				(font
					(size 1.27 1.27)
				)
				(justify mirror)
			)
		)
		(property "Value" ""
			(at 0 0 0)
			(layer "B.Fab")
			(effects
				(font
					(size 1.27 1.27)
				)
				(justify mirror)
			)
		)
		(duplicate_pad_numbers_are_jumpers no)
		(fp_line
			(start -1.524 -0.762)
			(end -1.524 0.762)
			(stroke
				(width 0.1524)
				(type default)
			)
			(layer "B.SilkS")
		)
		(fp_line
			(start -1.524 0.762)
			(end 1.524 0.762)
			(stroke
				(width 0.1524)
				(type default)
			)
			(layer "B.SilkS")
		)
		(fp_line
			(start 1.524 -0.762)
			(end -1.524 -0.762)
			(stroke
				(width 0.1524)
				(type default)
			)
			(layer "B.SilkS")
		)
		(fp_line
			(start 1.524 0.762)
			(end 1.524 -0.762)
			(stroke
				(width 0.1524)
				(type default)
			)
			(layer "B.SilkS")
		)
		(fp_line
			(start -1.1049 -0.724916)
			(end 1.1049 -0.724916)
			(stroke
				(width 0.1)
				(type default)
			)
			(layer "B.Fab")
		)
		(fp_line
			(start -1.1049 0.724916)
			(end -1.1049 -0.724916)
			(stroke
				(width 0.1)
				(type default)
			)
			(layer "B.Fab")
		)
		(fp_line
			(start 1.1049 -0.724916)
			(end 1.1049 0.724916)
			(stroke
				(width 0.1)
				(type default)
			)
			(layer "B.Fab")
		)
		(fp_line
			(start 1.1049 0.724916)
			(end -1.1049 0.724916)
			(stroke
				(width 0.1)
				(type default)
			)
			(layer "B.Fab")
		)
		(pad "1" smd rect
			(at 0.889 0)
			(size 1.016 1.27)
			(layers "B.Cu" "B.Mask" "B.Paste")
			(net "SW_P12V_PVCCINFAON_CPU0_FLT")
		)
		(pad "2" smd rect
			(at -0.889 0)
			(size 1.016 1.27)
			(layers "B.Cu" "B.Mask" "B.Paste")
			(net "GND")
		)
	)
)
